# S9S_MB_2U (Grand Teton) — schematic netlist excerpt (pin names and nets, part order shuffled) for the footprints in the layout excerpt that follows; sources: Cadence DE-HDL packaged netlist, KiCad conversion of 03242023_DA0F0TMBIJ0_F0T_Motherboard_J_brd_V01_OCP.brd

R661  Q_RES  1K 1% CHIP  pkg 0402LF  page 230 : A = PD_I3C_SPD_DDR_CPU1_OE_N ; B = GND

(kicad_pcb
	(version 20260206)
	(generator "pcbnew")
	(generator_version "10.0")
	(general
		(thickness 1.6)
		(legacy_teardrops no)
	)
	(paper "A4")
	(title_block
		(title "03242023_DA0F0TMBIJ0_F0T_Motherboard_J_brd_V01_OCP.brd")
		(comment 1 "Grand Teton / footprints 17-17 of 6105")
	)
	(layers
		(0 "F.Cu" signal "TOP")
		(4 "In1.Cu" signal "GND")
		(6 "In2.Cu" signal "IN1")
		(8 "In3.Cu" signal "GND1")
		(10 "In4.Cu" signal "IN2")
		(12 "In5.Cu" signal "GND2")
		(14 "In6.Cu" signal "IN3")
		(16 "In7.Cu" signal "GND3")
		(18 "In8.Cu" signal "VCC")
		(20 "In9.Cu" signal "VCC1")
		(22 "In10.Cu" signal "GND4")
		(24 "In11.Cu" signal "IN4")
		(26 "In12.Cu" signal "GND5")
		(28 "In13.Cu" signal "IN5")
		(30 "In14.Cu" signal "GND6")
		(32 "In15.Cu" signal "IN6")
		(34 "In16.Cu" signal "GND7")
		(2 "B.Cu" signal "BOTTOM")
		(9 "F.Adhes" user "F.Adhesive")
		(11 "B.Adhes" user "B.Adhesive")
		(13 "F.Paste" user "Package Geometry/Pastemask Top")
		(15 "B.Paste" user "Package Geometry/Pastemask Bottom")
		(5 "F.SilkS" user "Ref Des/Silkscreen Top")
		(7 "B.SilkS" user "Ref Des/Silkscreen Bottom")
		(1 "F.Mask" user "Board Geometry/Soldermask Top")
		(3 "B.Mask" user "Board Geometry/Soldermask Bottom")
		(17 "Dwgs.User" user "User.Drawings")
		(19 "Cmts.User" user "User.Comments")
		(21 "Eco1.User" user "User.Eco1")
		(23 "Eco2.User" user "User.Eco2")
		(25 "Edge.Cuts" user "Board Geometry/Outline")
		(27 "Margin" user)
		(31 "F.CrtYd" user "Package Geometry/Place Bound Top")
		(29 "B.CrtYd" user "Package Geometry/Place Bound Bottom")
		(35 "F.Fab" user "Ref Des/Assembly Top")
		(33 "B.Fab" user "Ref Des/Assembly Bottom")
	)
	(footprint ""
		(layer "F.Cu")
		(at 83.338924 -152.621742 90)
		(property "Reference" "R661"
			(at 0 0 90)
			(layer "F.SilkS")
			(hide yes)
			(effects
				(font
					(size 1.27 1.27)
				)
			)
		)
		(property "Value" ""
			(at 0 0 90)
			(layer "F.Fab")
			(effects
				(font
					(size 1.27 1.27)
				)
			)
		)
		(duplicate_pad_numbers_are_jumpers no)
		(fp_line
			(start 0.7874 -0.4064)
			(end 0.7874 0.4064)
			(stroke
				(width 0.1524)
				(type default)
			)
			(layer "F.SilkS")
		)
		(fp_line
			(start -0.7874 -0.4064)
			(end 0.7874 -0.4064)
			(stroke
				(width 0.1524)
				(type default)
			)
			(layer "F.SilkS")
		)
		(fp_line
			(start 0.7874 0.4064)
			(end -0.7874 0.4064)
			(stroke
				(width 0.1524)
				(type default)
			)
			(layer "F.SilkS")
		)
		(fp_line
			(start -0.7874 0.4064)
			(end -0.7874 -0.4064)
			(stroke
				(width 0.1524)
				(type default)
			)
			(layer "F.SilkS")
		)
		(fp_line
			(start -0.12065 -0.305054)
			(end -0.12065 -0.2794)
			(stroke
				(width 0.1)
				(type default)
			)
			(layer "F.Fab")
		)
		(fp_line
			(start -0.67945 -0.305054)
			(end -0.12065 -0.305054)
			(stroke
				(width 0.1)
				(type default)
			)
			(layer "F.Fab")
		)
		(fp_line
			(start 0.67945 -0.3048)
			(end 0.67945 0.3048)
			(stroke
				(width 0.1)
				(type default)
			)
			(layer "F.Fab")
		)
		(fp_line
			(start 0.12065 -0.3048)
			(end 0.67945 -0.3048)
			(stroke
				(width 0.1)
				(type default)
			)
			(layer "F.Fab")
		)
		(fp_line
			(start 0.12065 -0.2794)
			(end 0.12065 -0.3048)
			(stroke
				(width 0.1)
				(type default)
			)
			(layer "F.Fab")
		)
		(fp_line
			(start -0.12065 -0.2794)
			(end 0.12065 -0.2794)
			(stroke
				(width 0.1)
				(type default)
			)
			(layer "F.Fab")
		)
		(fp_line
			(start 0.120396 0.2794)
			(end -0.12065 0.2794)
			(stroke
				(width 0.1)
				(type default)
			)
			(layer "F.Fab")
		)
		(fp_line
			(start -0.12065 0.2794)
			(end -0.12065 0.3048)
			(stroke
				(width 0.1)
				(type default)
			)
			(layer "F.Fab")
		)
		(fp_line
			(start 0.67945 0.3048)
			(end 0.120396 0.3048)
			(stroke
				(width 0.1)
				(type default)
			)
			(layer "F.Fab")
		)
		(fp_line
			(start 0.120396 0.3048)
			(end 0.120396 0.2794)
			(stroke
				(width 0.1)
				(type default)
			)
			(layer "F.Fab")
		)
		(fp_line
			(start -0.12065 0.3048)
			(end -0.67945 0.3048)
			(stroke
				(width 0.1)
				(type default)
			)
			(layer "F.Fab")
		)
		(fp_line
			(start -0.67945 0.3048)
			(end -0.67945 -0.305054)
			(stroke
				(width 0.1)
				(type default)
			)
			(layer "F.Fab")
		)
		(pad "1" smd circle
			(at -0.40005 0 90)
			(size 0 0)
			(layers "F.Cu" "F.Mask" "F.Paste")
			(net "PD_I3C_SPD_DDR_CPU1_OE_N")
		)
		(pad "2" smd circle
			(at 0.40005 0 90)
			(size 0 0)
			(layers "F.Cu" "F.Mask" "F.Paste")
			(net "GND")
		)
	)
)
